# BASEBOARD_FAB2 (Tioga Pass) — schematic netlist excerpt (pin names and nets, part order shuffled) for the footprints in the layout excerpt that follows; sources: Cadence DE-HDL packaged netlist, KiCad conversion of Wiwynn_Tioga_Pass_MB.brd

C8F17  CAP_A  0.1UF 16V 10% X7R  pkg 0402V  page 198 : A = P5V_STBY ; B = GND
C3N18  CAP_A  1.0UF 6.3V 10% X6S  pkg 0402V  page 132 : A = PVNN_PCH_STBY ; B = GND
R25W181  RES  0.0 5% CHIP  pkg 0402  page 147 : A = RST_RSMRST_N ; B = BMC_RSMRST_B_N

(kicad_pcb
	(version 20260206)
	(generator "pcbnew")
	(generator_version "10.0")
	(general
		(thickness 1.6)
		(legacy_teardrops no)
	)
	(paper "A4")
	(title_block
		(title "Wiwynn_Tioga_Pass_MB.brd")
		(comment 1 "Tioga Pass / footprints 3878-3880 of 4770")
	)
	(layers
		(0 "F.Cu" signal "TOP")
		(4 "In1.Cu" signal "L2GND")
		(6 "In2.Cu" signal "L3")
		(8 "In3.Cu" signal "L4GND")
		(10 "In4.Cu" signal "L5")
		(12 "In5.Cu" signal "L6GND")
		(14 "In6.Cu" signal "L7VCC")
		(16 "In7.Cu" signal "L8VCC")
		(18 "In8.Cu" signal "L9GND")
		(20 "In9.Cu" signal "L10")
		(22 "In10.Cu" signal "L11GND")
		(24 "In11.Cu" signal "L12")
		(26 "In12.Cu" signal "L13GND")
		(2 "B.Cu" signal "BOTTOM")
		(9 "F.Adhes" user "F.Adhesive")
		(11 "B.Adhes" user "B.Adhesive")
		(13 "F.Paste" user "Package Geometry/Pastemask Top")
		(15 "B.Paste" user "Package Geometry/Pastemask Bottom")
		(5 "F.SilkS" user "Ref Des/Silkscreen Top")
		(7 "B.SilkS" user "Ref Des/Silkscreen Bottom")
		(1 "F.Mask" user "Board Geometry/Soldermask Top")
		(3 "B.Mask" user "Board Geometry/Soldermask Bottom")
		(17 "Dwgs.User" user "User.Drawings")
		(19 "Cmts.User" user "User.Comments")
		(21 "Eco1.User" user "User.Eco1")
		(23 "Eco2.User" user "User.Eco2")
		(25 "Edge.Cuts" user "Board Geometry/Outline")
		(27 "Margin" user)
		(31 "F.CrtYd" user "Package Geometry/Place Bound Top")
		(29 "B.CrtYd" user "Package Geometry/Place Bound Bottom")
		(35 "F.Fab" user "Ref Des/Assembly Top")
		(33 "B.Fab" user "Ref Des/Assembly Bottom")
	)
	(footprint ""
		(layer "B.Cu")
		(at 475.187518 -15.517876 180)
		(property "Reference" "C8F17"
			(at 0 0 0)
			(layer "B.SilkS")
			(hide yes)
			(effects
				(font
					(size 1.27 1.27)
				)
				(justify mirror)
			)
		)
		(property "Value" ""
			(at 0 0 0)
			(layer "B.Fab")
			(effects
				(font
					(size 1.27 1.27)
				)
				(justify mirror)
			)
		)
		(duplicate_pad_numbers_are_jumpers no)
		(fp_rect
			(start 0.3048 0.9906)
			(end -0.3048 -0.1016)
			(stroke
				(width 0)
				(type default)
			)
			(fill no)
			(layer "B.CrtYd")
		)
		(fp_line
			(start 0.3048 0.9906)
			(end -0.3048 0.9906)
			(stroke
				(width 0.1)
				(type default)
			)
			(layer "B.Fab")
		)
		(fp_line
			(start 0.3048 -0.1016)
			(end 0.3048 0.9906)
			(stroke
				(width 0.1)
				(type default)
			)
			(layer "B.Fab")
		)
		(fp_line
			(start -0.3048 0.9906)
			(end -0.3048 -0.1016)
			(stroke
				(width 0.1)
				(type default)
			)
			(layer "B.Fab")
		)
		(fp_line
			(start -0.3048 -0.1016)
			(end 0.3048 -0.1016)
			(stroke
				(width 0.1)
				(type default)
			)
			(layer "B.Fab")
		)
		(pad "1" smd rect
			(at 0 0)
			(size 0.508 0.508)
			(layers "B.Cu" "B.Mask" "B.Paste")
			(net "P5V_STBY")
		)
		(pad "2" smd rect
			(at 0 0.889)
			(size 0.508 0.508)
			(layers "B.Cu" "B.Mask" "B.Paste")
			(net "GND")
		)
		(zone
			(layer "B.Cu")
			(hatch none 0.5)
			(connect_pads
				(clearance 0)
			)
			(min_thickness 0.25)
			(keepout
				(tracks not_allowed)
				(vias allowed)
				(pads allowed)
				(copperpour not_allowed)
				(footprints allowed)
			)
			(placement
				(enabled no)
				(sheetname "")
			)
			(fill
				(thermal_gap 0.5)
				(thermal_bridge_width 0.5)
				(island_removal_mode 0)
			)
			(polygon
				(pts
					(xy 474.933518 -16.152876) (xy 474.933518 -15.771876) (xy 475.441518 -15.771876) (xy 475.441518 -16.152876)
				)
			)
		)
		(zone
			(layer "B.Cu")
			(hatch none 0.5)
			(connect_pads
				(clearance 0)
			)
			(min_thickness 0.25)
			(keepout
				(tracks allowed)
				(vias not_allowed)
				(pads allowed)
				(copperpour not_allowed)
				(footprints allowed)
			)
			(placement
				(enabled no)
				(sheetname "")
			)
			(fill
				(thermal_gap 0.5)
				(thermal_bridge_width 0.5)
				(island_removal_mode 0)
			)
			(polygon
				(pts
					(xy 474.933518 -16.152876) (xy 474.933518 -15.771876) (xy 475.441518 -15.771876) (xy 475.441518 -16.152876)
				)
			)
		)
	)
	(footprint ""
		(layer "B.Cu")
		(at 385.33705 -107.05465 90)
		(property "Reference" "C3N18"
			(at 0 0 90)
			(layer "B.SilkS")
			(hide yes)
			(effects
				(font
					(size 1.27 1.27)
				)
				(justify mirror)
			)
		)
		(property "Value" ""
			(at 0 0 90)
			(layer "B.Fab")
			(effects
				(font
					(size 1.27 1.27)
				)
				(justify mirror)
			)
		)
		(duplicate_pad_numbers_are_jumpers no)
		(fp_rect
			(start 0.2794 0.9144)
			(end -0.2794 -0.1143)
			(stroke
				(width 0)
				(type default)
			)
			(fill no)
			(layer "B.CrtYd")
		)
		(fp_line
			(start 0.2794 -0.1143)
			(end -0.2794 -0.1143)
			(stroke
				(width 0.1)
				(type default)
			)
			(layer "B.Fab")
		)
		(fp_line
			(start -0.2794 -0.1143)
			(end -0.2794 0.9144)
			(stroke
				(width 0.1)
				(type default)
			)
			(layer "B.Fab")
		)
		(fp_line
			(start 0.2794 0.9144)
			(end 0.2794 -0.1143)
			(stroke
				(width 0.1)
				(type default)
			)
			(layer "B.Fab")
		)
		(fp_line
			(start -0.2794 0.9144)
			(end 0.2794 0.9144)
			(stroke
				(width 0.1)
				(type default)
			)
			(layer "B.Fab")
		)
		(pad "1" smd custom
			(at 0 0)
			(size 0.10414 0.10414)
			(layers "B.Cu" "B.Mask" "B.Paste")
			(net "PVNN_PCH_STBY")
			(options
				(clearance outline)
				(anchor circle)
			)
			(primitives
				(gr_poly
					(pts
						(xy -0.20828 -0.08636) (xy -0.20828 0.08636) (xy -0.08636 0.20828) (xy 0.086614 0.20828) (xy 0.20828 0.086614)
						(xy 0.20828 -0.08636) (xy 0.08636 -0.20828) (xy -0.08636 -0.20828)
					)
					(width 0)
					(fill yes)
				)
			)
		)
		(pad "2" smd custom
			(at 0 0.8001)
			(size 0.10414 0.10414)
			(layers "B.Cu" "B.Mask" "B.Paste")
			(net "GND")
			(options
				(clearance outline)
				(anchor circle)
			)
			(primitives
				(gr_poly
					(pts
						(xy -0.20828 -0.08636) (xy -0.20828 0.08636) (xy -0.08636 0.20828) (xy 0.086614 0.20828) (xy 0.20828 0.086614)
						(xy 0.20828 -0.08636) (xy 0.08636 -0.20828) (xy -0.08636 -0.20828)
					)
					(width 0)
					(fill yes)
				)
			)
		)
		(zone
			(layer "B.Cu")
			(hatch none 0.5)
			(connect_pads
				(clearance 0)
			)
			(min_thickness 0.25)
			(keepout
				(tracks allowed)
				(vias not_allowed)
				(pads allowed)
				(copperpour not_allowed)
				(footprints allowed)
			)
			(placement
				(enabled no)
				(sheetname "")
			)
			(fill
				(thermal_gap 0.5)
				(thermal_bridge_width 0.5)
				(island_removal_mode 0)
			)
			(polygon
				(pts
					(xy 385.5466 -107.14228) (xy 385.9276 -107.14228) (xy 385.9276 -106.96702) (xy 385.5466 -106.966766)
				)
			)
		)
		(zone
			(layer "B.Cu")
			(hatch none 0.5)
			(connect_pads
				(clearance 0)
			)
			(min_thickness 0.25)
			(keepout
				(tracks not_allowed)
				(vias allowed)
				(pads allowed)
				(copperpour not_allowed)
				(footprints allowed)
			)
			(placement
				(enabled no)
				(sheetname "")
			)
			(fill
				(thermal_gap 0.5)
				(thermal_bridge_width 0.5)
				(island_removal_mode 0)
			)
			(polygon
				(pts
					(xy 385.5466 -107.14228) (xy 385.9276 -107.14228) (xy 385.9276 -106.96702) (xy 385.5466 -106.966766)
				)
			)
		)
	)
	(footprint ""
		(layer "B.Cu")
		(at 394.251434 -33.139634)
		(property "Reference" "R25W181"
			(at 0.8382 -0.67818 0)
			(unlocked yes)
			(layer "B.SilkS")
			(effects
				(font
					(size 0.4064 0.254)
					(thickness 0.1524)
				)
				(justify left mirror)
			)
		)
		(property "Value" ""
			(at 0 0 0)
			(layer "B.Fab")
			(effects
				(font
					(size 1.27 1.27)
				)
				(justify mirror)
			)
		)
		(duplicate_pad_numbers_are_jumpers no)
		(fp_poly
			(pts
				(xy 0.2794 -0.1016) (xy -0.2794 -0.1016) (xy -0.2794 0.9906) (xy 0.2794 0.9906)
			)
			(stroke
				(width 0)
				(type default)
			)
			(fill no)
			(layer "B.CrtYd")
		)
		(fp_line
			(start -0.2794 -0.1016)
			(end 0.2794 -0.1016)
			(stroke
				(width 0.1)
				(type default)
			)
			(layer "B.Fab")
		)
		(fp_line
			(start -0.2794 0.9906)
			(end -0.2794 -0.1016)
			(stroke
				(width 0.1)
				(type default)
			)
			(layer "B.Fab")
		)
		(fp_line
			(start 0.2794 -0.1016)
			(end 0.2794 0.9906)
			(stroke
				(width 0.1)
				(type default)
			)
			(layer "B.Fab")
		)
		(fp_line
			(start 0.2794 0.9906)
			(end -0.2794 0.9906)
			(stroke
				(width 0.1)
				(type default)
			)
			(layer "B.Fab")
		)
		(pad "1" smd rect
			(at 0 0 180)
			(size 0.508 0.508)
			(layers "B.Cu" "B.Mask" "B.Paste")
			(net "RST_RSMRST_N")
		)
		(pad "2" smd rect
			(at 0 0.889 180)
			(size 0.508 0.508)
			(layers "B.Cu" "B.Mask" "B.Paste")
			(net "BMC_RSMRST_B_N")
		)
		(zone
			(layer "B.Cu")
			(hatch none 0.5)
			(connect_pads
				(clearance 0)
			)
			(min_thickness 0.25)
			(keepout
				(tracks allowed)
				(vias not_allowed)
				(pads allowed)
				(copperpour not_allowed)
				(footprints allowed)
			)
			(placement
				(enabled no)
				(sheetname "")
			)
			(fill
				(thermal_gap 0.5)
				(thermal_bridge_width 0.5)
				(island_removal_mode 0)
			)
			(polygon
				(pts
					(xy 394.505434 -32.885634) (xy 393.997434 -32.885634) (xy 393.997434 -32.504634) (xy 394.505434 -32.504634)
				)
			)
		)
		(zone
			(layer "B.Cu")
			(hatch none 0.5)
			(connect_pads
				(clearance 0)
			)
			(min_thickness 0.25)
			(keepout
				(tracks not_allowed)
				(vias allowed)
				(pads allowed)
				(copperpour not_allowed)
				(footprints allowed)
			)
			(placement
				(enabled no)
				(sheetname "")
			)
			(fill
				(thermal_gap 0.5)
				(thermal_bridge_width 0.5)
				(island_removal_mode 0)
			)
			(polygon
				(pts
					(xy 394.505434 -32.504634) (xy 393.997434 -32.504634) (xy 393.997434 -32.885634) (xy 394.505434 -32.885634)
				)
			)
		)
	)
)
